# S9S_MB_2U (Grand Teton) — schematic netlist excerpt (pin names and nets, part order shuffled) for the footprints in the layout excerpt that follows; sources: Cadence DE-HDL packaged netlist, KiCad conversion of 03242023_DA0F0TMBIJ0_F0T_Motherboard_J_brd_V01_OCP.brd

C415  Q_CAP  22UF 4V 20% X6S  pkg C0402  page 74 : A = PVCCFA_EHV_FIVRA_CPU0 ; B = GND

U255  74LVC2G07DW7  74LVC2G07DW-7 IC  pkg SOT363_0-65_2X1-25XC  page 150
  \1a\  = GPU_NVS_PWR_BRAKE_N
  GND  = GND
  \2a\  = GPU_FPGA_EROT_RST_N
  \2y\  = GPU_FPGA_EROT_RST_BUF_R_N
  VCC  = P3V3_AUX
  \1y\  = GPU_NVS_PWR_BRAKE_N_R

(kicad_pcb
	(version 20260206)
	(generator "pcbnew")
	(generator_version "10.0")
	(general
		(thickness 1.6)
		(legacy_teardrops no)
	)
	(paper "A4")
	(title_block
		(title "03242023_DA0F0TMBIJ0_F0T_Motherboard_J_brd_V01_OCP.brd")
		(comment 1 "Grand Teton / footprints 3028-3029 of 6105")
	)
	(layers
		(0 "F.Cu" signal "TOP")
		(4 "In1.Cu" signal "GND")
		(6 "In2.Cu" signal "IN1")
		(8 "In3.Cu" signal "GND1")
		(10 "In4.Cu" signal "IN2")
		(12 "In5.Cu" signal "GND2")
		(14 "In6.Cu" signal "IN3")
		(16 "In7.Cu" signal "GND3")
		(18 "In8.Cu" signal "VCC")
		(20 "In9.Cu" signal "VCC1")
		(22 "In10.Cu" signal "GND4")
		(24 "In11.Cu" signal "IN4")
		(26 "In12.Cu" signal "GND5")
		(28 "In13.Cu" signal "IN5")
		(30 "In14.Cu" signal "GND6")
		(32 "In15.Cu" signal "IN6")
		(34 "In16.Cu" signal "GND7")
		(2 "B.Cu" signal "BOTTOM")
		(9 "F.Adhes" user "F.Adhesive")
		(11 "B.Adhes" user "B.Adhesive")
		(13 "F.Paste" user "Package Geometry/Pastemask Top")
		(15 "B.Paste" user "Package Geometry/Pastemask Bottom")
		(5 "F.SilkS" user "Ref Des/Silkscreen Top")
		(7 "B.SilkS" user "Ref Des/Silkscreen Bottom")
		(1 "F.Mask" user "Board Geometry/Soldermask Top")
		(3 "B.Mask" user "Board Geometry/Soldermask Bottom")
		(17 "Dwgs.User" user "User.Drawings")
		(19 "Cmts.User" user "User.Comments")
		(21 "Eco1.User" user "User.Eco1")
		(23 "Eco2.User" user "User.Eco2")
		(25 "Edge.Cuts" user "Board Geometry/Outline")
		(27 "Margin" user)
		(31 "F.CrtYd" user "Package Geometry/Place Bound Top")
		(29 "B.CrtYd" user "Package Geometry/Place Bound Bottom")
		(35 "F.Fab" user "Ref Des/Assembly Top")
		(33 "B.Fab" user "Ref Des/Assembly Bottom")
	)
	(footprint ""
		(layer "F.Cu")
		(at 366.48263 -240.276888 90)
		(property "Reference" "C415"
			(at 0 0 90)
			(layer "F.SilkS")
			(hide yes)
			(effects
				(font
					(size 1.27 1.27)
				)
			)
		)
		(property "Value" ""
			(at 0 0 90)
			(layer "F.Fab")
			(effects
				(font
					(size 1.27 1.27)
				)
			)
		)
		(duplicate_pad_numbers_are_jumpers no)
		(fp_line
			(start 0.7874 -0.4064)
			(end 0.7874 0.4064)
			(stroke
				(width 0.1524)
				(type default)
			)
			(layer "F.SilkS")
		)
		(fp_line
			(start -0.7874 -0.4064)
			(end 0.7874 -0.4064)
			(stroke
				(width 0.1524)
				(type default)
			)
			(layer "F.SilkS")
		)
		(fp_line
			(start 0.7874 0.4064)
			(end -0.7874 0.4064)
			(stroke
				(width 0.1524)
				(type default)
			)
			(layer "F.SilkS")
		)
		(fp_line
			(start -0.7874 0.4064)
			(end -0.7874 -0.4064)
			(stroke
				(width 0.1524)
				(type default)
			)
			(layer "F.SilkS")
		)
		(fp_line
			(start -0.12065 -0.305054)
			(end -0.12065 -0.2794)
			(stroke
				(width 0.1)
				(type default)
			)
			(layer "F.Fab")
		)
		(fp_line
			(start -0.67945 -0.305054)
			(end -0.12065 -0.305054)
			(stroke
				(width 0.1)
				(type default)
			)
			(layer "F.Fab")
		)
		(fp_line
			(start 0.67945 -0.3048)
			(end 0.67945 0.3048)
			(stroke
				(width 0.1)
				(type default)
			)
			(layer "F.Fab")
		)
		(fp_line
			(start 0.12065 -0.3048)
			(end 0.67945 -0.3048)
			(stroke
				(width 0.1)
				(type default)
			)
			(layer "F.Fab")
		)
		(fp_line
			(start 0.12065 -0.2794)
			(end 0.12065 -0.3048)
			(stroke
				(width 0.1)
				(type default)
			)
			(layer "F.Fab")
		)
		(fp_line
			(start -0.12065 -0.2794)
			(end 0.12065 -0.2794)
			(stroke
				(width 0.1)
				(type default)
			)
			(layer "F.Fab")
		)
		(fp_line
			(start 0.120396 0.2794)
			(end -0.12065 0.2794)
			(stroke
				(width 0.1)
				(type default)
			)
			(layer "F.Fab")
		)
		(fp_line
			(start -0.12065 0.2794)
			(end -0.12065 0.3048)
			(stroke
				(width 0.1)
				(type default)
			)
			(layer "F.Fab")
		)
		(fp_line
			(start 0.67945 0.3048)
			(end 0.120396 0.3048)
			(stroke
				(width 0.1)
				(type default)
			)
			(layer "F.Fab")
		)
		(fp_line
			(start 0.120396 0.3048)
			(end 0.120396 0.2794)
			(stroke
				(width 0.1)
				(type default)
			)
			(layer "F.Fab")
		)
		(fp_line
			(start -0.12065 0.3048)
			(end -0.67945 0.3048)
			(stroke
				(width 0.1)
				(type default)
			)
			(layer "F.Fab")
		)
		(fp_line
			(start -0.67945 0.3048)
			(end -0.67945 -0.305054)
			(stroke
				(width 0.1)
				(type default)
			)
			(layer "F.Fab")
		)
		(pad "1" smd circle
			(at -0.40005 0 90)
			(size 0 0)
			(layers "F.Cu" "F.Mask" "F.Paste")
			(net "PVCCFA_EHV_FIVRA_CPU0")
		)
		(pad "2" smd circle
			(at 0.40005 0 90)
			(size 0 0)
			(layers "F.Cu" "F.Mask" "F.Paste")
			(net "GND")
		)
	)
	(footprint ""
		(layer "F.Cu")
		(at 105.696004 -393.711684 180)
		(property "Reference" "U255"
			(at 1.799844 -3.027426 0)
			(unlocked yes)
			(layer "F.SilkS")
			(effects
				(font
					(size 0.7874 0.5842)
					(thickness 0.1524)
				)
				(justify left)
			)
		)
		(property "Value" ""
			(at 0 0 180)
			(layer "F.Fab")
			(effects
				(font
					(size 1.27 1.27)
				)
			)
		)
		(duplicate_pad_numbers_are_jumpers no)
		(fp_line
			(start 1.38176 1.100074)
			(end 1.38176 -1.100074)
			(stroke
				(width 0.1524)
				(type default)
			)
			(layer "F.SilkS")
		)
		(fp_line
			(start 1.38176 -1.100074)
			(end 0.592074 -1.100074)
			(stroke
				(width 0.1524)
				(type default)
			)
			(layer "F.SilkS")
		)
		(fp_line
			(start 0.456184 1.100074)
			(end 1.38176 1.100074)
			(stroke
				(width 0.1524)
				(type default)
			)
			(layer "F.SilkS")
		)
		(fp_line
			(start -0.592074 -1.100074)
			(end -1.38176 -1.100074)
			(stroke
				(width 0.1524)
				(type default)
			)
			(layer "F.SilkS")
		)
		(fp_line
			(start -1.38176 1.100074)
			(end -0.305816 1.100074)
			(stroke
				(width 0.1524)
				(type default)
			)
			(layer "F.SilkS")
		)
		(fp_line
			(start -1.38176 -1.100074)
			(end -1.38176 1.100074)
			(stroke
				(width 0.1524)
				(type default)
			)
			(layer "F.SilkS")
		)
		(fp_poly
			(pts
				(xy -1.260856 -1.255014) (xy -1.728216 -1.410716) (xy -1.416812 -1.722374)
			)
			(stroke
				(width 0)
				(type default)
			)
			(fill yes)
			(layer "F.SilkS")
		)
		(fp_line
			(start 0.674878 1.100074)
			(end 0.674878 -1.100074)
			(stroke
				(width 0.1)
				(type default)
			)
			(layer "F.Fab")
		)
		(fp_line
			(start 0.674878 -1.100074)
			(end -0.674878 -1.100074)
			(stroke
				(width 0.1)
				(type default)
			)
			(layer "F.Fab")
		)
		(fp_line
			(start -0.674878 1.100074)
			(end 0.674878 1.100074)
			(stroke
				(width 0.1)
				(type default)
			)
			(layer "F.Fab")
		)
		(fp_line
			(start -0.674878 -1.100074)
			(end -0.674878 1.100074)
			(stroke
				(width 0.1)
				(type default)
			)
			(layer "F.Fab")
		)
		(fp_poly
			(pts
				(xy -1.9431 -0.870204) (xy -1.50241 -0.649986) (xy -1.9431 -0.429768)
			)
			(stroke
				(width 0)
				(type default)
			)
			(fill yes)
			(layer "F.Fab")
		)
		(pad "1" smd rect
			(at -0.94996 -0.649986 90)
			(size 0.4318 0.6096)
			(layers "F.Cu" "F.Mask" "F.Paste")
			(net "GPU_NVS_PWR_BRAKE_N")
		)
		(pad "2" smd rect
			(at -0.94996 0 90)
			(size 0.4318 0.6096)
			(layers "F.Cu" "F.Mask" "F.Paste")
			(net "GND")
		)
		(pad "3" smd rect
			(at -0.94996 0.649986 90)
			(size 0.4318 0.6096)
			(layers "F.Cu" "F.Mask" "F.Paste")
			(net "GPU_FPGA_EROT_RST_N")
		)
		(pad "4" smd rect
			(at 0.94996 0.649986 90)
			(size 0.4318 0.6096)
			(layers "F.Cu" "F.Mask" "F.Paste")
			(net "GPU_FPGA_EROT_RST_BUF_R_N")
		)
		(pad "5" smd rect
			(at 0.94996 0 90)
			(size 0.4318 0.6096)
			(layers "F.Cu" "F.Mask" "F.Paste")
			(net "P3V3_AUX")
		)
		(pad "6" smd rect
			(at 0.94996 -0.649986 90)
			(size 0.4318 0.6096)
			(layers "F.Cu" "F.Mask" "F.Paste")
			(net "GPU_NVS_PWR_BRAKE_N_R")
		)
	)
)
